(kicad_pcb
	(version 20241229)
	(generator "pcbnew")
	(generator_version "9.0")
	(general
		(thickness 1.552)
		(legacy_teardrops no)
	)
	(paper "A4")
	(title_block
		(date "2023-07-25")
		(rev "1.1.4")
		(comment 9 "footprint 75 of 379 (U15), pads 89-100 of 100")
	)
	(layers
		(0 "F.Cu" signal)
		(4 "In1.Cu" signal)
		(6 "In2.Cu" signal)
		(8 "In3.Cu" signal)
		(10 "In4.Cu" signal)
		(12 "In5.Cu" signal)
		(14 "In6.Cu" signal)
		(2 "B.Cu" signal)
		(9 "F.Adhes" user "F.Adhesive")
		(11 "B.Adhes" user "B.Adhesive")
		(13 "F.Paste" user)
		(15 "B.Paste" user)
		(5 "F.SilkS" user "F.Silkscreen")
		(7 "B.SilkS" user "B.Silkscreen")
		(1 "F.Mask" user)
		(3 "B.Mask" user)
		(17 "Dwgs.User" user "User.Drawings")
		(19 "Cmts.User" user "User.Comments")
		(21 "Eco1.User" user "User.Eco1")
		(23 "Eco2.User" user "User.Eco2")
		(25 "Edge.Cuts" user)
		(27 "Margin" user)
		(31 "F.CrtYd" user "F.Courtyard")
		(29 "B.CrtYd" user "B.Courtyard")
		(35 "F.Fab" user)
		(33 "B.Fab" user)
	)
	(footprint "antmicro-footprints:BGA-100_11x11mm_Layout10x10_P1mm"
		(layer "F.Cu")
		(at 95.609 77.893)
		(property "Reference" "U15"
			(at 0 -6.15 0)
			(layer "F.SilkS")
			(effects
				(font
					(size 0.7 0.7)
					(thickness 0.15)
				)
				(justify left bottom)
			)
		)
		(property "Value" "GS2971A"
			(at 0 7 0)
			(layer "F.Fab")
			(effects
				(font
					(size 0.7 0.7)
					(thickness 0.15)
				)
				(justify left bottom)
			)
		)
		(property "Datasheet" "https://semtech.my.salesforce.com/sfc/p/#E0000000JelG/a/44000000MD3i/kpmMkrmUWgHlbCOwdLzVohMm1SDPoVH85guEGK.KXTc"
			(at 0 0 0)
			(layer "F.Fab")
			(hide yes)
			(effects
				(font
					(size 1.27 1.27)
					(thickness 0.15)
				)
			)
		)
		(property "Description" "SDI receiver"
			(at 0 0 0)
			(layer "F.Fab")
			(hide yes)
			(effects
				(font
					(size 1.27 1.27)
					(thickness 0.15)
				)
			)
		)
		(property "Author" "Antmicro"
			(at 0 0 0)
			(layer "F.Fab")
			(hide yes)
			(effects
				(font
					(size 1 1)
					(thickness 0.15)
				)
			)
		)
		(property "License" "Apache-2.0"
			(at 0 0 0)
			(layer "F.Fab")
			(hide yes)
			(effects
				(font
					(size 1 1)
					(thickness 0.15)
				)
			)
		)
		(property "MPN" "GS2971A"
			(at 0 0 0)
			(layer "F.Fab")
			(hide yes)
			(effects
				(font
					(size 1 1)
					(thickness 0.15)
				)
			)
		)
		(property "Manufacturer" "Semtech"
			(at 0 0 0)
			(layer "F.Fab")
			(hide yes)
			(effects
				(font
					(size 1 1)
					(thickness 0.15)
				)
			)
		)
		(sheetname "/SDI/")
		(sheetfile "sdi.kicad_sch")
		(attr smd)
		(pad "J9" smd circle
			(at 3.482 3.507)
			(size 0.5 0.5)
			(layers "F.Cu" "F.Mask" "F.Paste")
			(net 187 "/SDI/SDI_D4")
			(pinfunction "DOUT04")
			(pintype "output")
		)
		(pad "J10" smd circle
			(at 4.482 3.507)
			(size 0.5 0.5)
			(layers "F.Cu" "F.Mask" "F.Paste")
			(net 188 "/SDI/SDI_D5")
			(pinfunction "DOUT05")
			(pintype "output")
		)
		(pad "K1" smd circle
			(at -4.518 4.506)
			(size 0.5 0.5)
			(layers "F.Cu" "F.Mask" "F.Paste")
			(net 48 "/SDI/SDO_N")
			(pinfunction "SDO-")
			(pintype "output")
		)
		(pad "K2" smd circle
			(at -3.519 4.506)
			(size 0.5 0.5)
			(layers "F.Cu" "F.Mask" "F.Paste")
			(net 176 "/SDI/STANDBY")
			(pinfunction "STANDBY")
			(pintype "input")
		)
		(pad "K3" smd circle
			(at -2.519 4.506)
			(size 0.5 0.5)
			(layers "F.Cu" "F.Mask" "F.Paste")
			(net 24 "AUDIO_OUT_CH3_4")
			(pinfunction "AOUT_{3/4}")
			(pintype "output")
		)
		(pad "K4" smd circle
			(at -1.518 4.506)
			(size 0.5 0.5)
			(layers "F.Cu" "F.Mask" "F.Paste")
			(net 26 "AUDIO_MCLK")
			(pinfunction "AMCLK")
			(pintype "output")
		)
		(pad "K5" smd circle
			(at -0.519 4.506)
			(size 0.5 0.5)
			(layers "F.Cu" "F.Mask" "F.Paste")
			(net 25 "AUDIO_OUT_CH7_8")
			(pinfunction "AOUT_{7/8}")
			(pintype "output")
		)
		(pad "K6" smd circle
			(at 0.481 4.506)
			(size 0.5 0.5)
			(layers "F.Cu" "F.Mask" "F.Paste")
			(net 45 "/SDI/XTAL1")
			(pinfunction "XTAL1")
			(pintype "input")
		)
		(pad "K7" smd circle
			(at 1.481 4.506)
			(size 0.5 0.5)
			(layers "F.Cu" "F.Mask" "F.Paste")
			(net 2 "+3V3")
			(pinfunction "IO_{VDD}")
			(pintype "passive")
		)
		(pad "K8" smd circle
			(at 2.482 4.506)
			(size 0.5 0.5)
			(layers "F.Cu" "F.Mask" "F.Paste")
			(net 192 "/SDI/SDI_D0")
			(pinfunction "DOUT0")
			(pintype "output")
		)
		(pad "K9" smd circle
			(at 3.482 4.506)
			(size 0.5 0.5)
			(layers "F.Cu" "F.Mask" "F.Paste")
			(net 190 "/SDI/SDI_D2")
			(pinfunction "DOUT02")
			(pintype "output")
		)
		(pad "K10" smd circle
			(at 4.482 4.506)
			(size 0.5 0.5)
			(layers "F.Cu" "F.Mask" "F.Paste")
			(net 189 "/SDI/SDI_D3")
			(pinfunction "DOUT03")
			(pintype "output")
		)
	)
)
